FILE_TYPE = MACRO_DRAWING;
SET COLOR_WIRE YELLOW;
SET COLOR_PROP ORANGE;
SET COLOR_DOT WHITE;
SET COLOR_ARC YELLOW;
SET COLOR_BODY GREEN;
SET COLOR_NOTE PURPLE;
SET PROP_DISPLAY VALUE;
SET PAGE_NUMBER P164;
FORCEADD Q_CAP..1
(-8250 7825);
FORCEPROP 1 LAST LOCATION PC1648
J 0
(-8200 7925);
DISPLAY 0.787234 (-8200 7925);
FORCEPROP 0 LAST $SEC 1
J 0
(-8200 7975);
DISPLAY 0.680851 (-8200 7975);
PAINT MONO (-8200 7975);
DISPLAY INVISIBLE (-8200 7975);
FORCEPROP 0 LAST CDS_SEC 1
J 0
(-8200 7975);
DISPLAY 1.021277 (-8200 7975);
DISPLAY INVISIBLE (-8200 7975);
FORCEPROP 1 LASTPIN (-8250 7925) $PN 1
J 0
(-8240 7905);
DISPLAY 0.787234 (-8240 7905);
PAINT MONO (-8240 7905);
FORCEPROP 1 LASTPIN (-8250 7725) $PN 2
J 0
(-8240 7705);
DISPLAY 0.787234 (-8240 7705);
PAINT MONO (-8240 7705);
FORCEPROP 1 LAST VALUE 100NF
J 0
(-8200 7875);
DISPLAY 0.787234 (-8200 7875);
FORCEPROP 1 LAST PACK_TYPE C0402
J 0
(-8200 7625);
DISPLAY 0.787234 (-8200 7625);
FORCEPROP 1 LAST VOLTAGE 50V
J 0
(-8200 7825);
DISPLAY 0.787234 (-8200 7825);
FORCEPROP 1 LAST TOLERANCE 10%
J 0
(-8200 7775);
DISPLAY 0.787234 (-8200 7775);
FORCEPROP 1 LAST MATERIAL X7R
J 0
(-8200 7725);
DISPLAY 0.787234 (-8200 7725);
FORCEPROP 1 LAST PART_NUMBER CH4106K1B01
J 0
(-8200 7675);
DISPLAY 0.787234 (-8200 7675);
FORCEPROP 2 LAST CDS_LIB pure_quanta
J 0
(-8250 7825);
DISPLAY INVISIBLE (-8250 7825);
FORCEPROP 1 LAST PATH I1
J 0
(-8200 7975);
DISPLAY 0.978723 (-8200 7975);
PAINT WHITE (-8200 7975);
DISPLAY INVISIBLE (-8200 7975);
FORCEADD Q_CAP..1
R 2
(-6900 6525);
FORCEPROP 1 LAST LOCATION PC1848
J 2
(-6675 6650);
DISPLAY 0.617021 (-6675 6650);
PAINT AQUA (-6675 6650);
FORCEPROP 2 LAST SEC 1
J 0
(-6950 6721);
DISPLAY 0.680851 (-6950 6721);
PAINT MONO (-6950 6721);
DISPLAY INVISIBLE (-6950 6721);
FORCEPROP 1 LASTPIN (-6900 6625) $PN 1
J 2
(-6854 6596);
DISPLAY 0.617021 (-6854 6596);
FORCEPROP 1 LASTPIN (-6900 6425) $PN 2
J 2
(-6856 6420);
DISPLAY 0.617021 (-6856 6420);
FORCEPROP 1 LAST VALUE 1UF
J 0
(-6800 6595);
DISPLAY 0.617021 (-6800 6595);
PAINT SKYBLUE (-6800 6595);
FORCEPROP 1 LAST VOLTAGE 25V
J 0
(-6800 6546);
DISPLAY 0.617021 (-6800 6546);
PAINT SKYBLUE (-6800 6546);
FORCEPROP 1 LAST PACK_TYPE C0402
J 0
(-6800 6399);
DISPLAY 0.617021 (-6800 6399);
PAINT SKYBLUE (-6800 6399);
FORCEPROP 1 LAST MATERIAL X6S
J 0
(-6800 6448);
DISPLAY 0.617021 (-6800 6448);
PAINT SKYBLUE (-6800 6448);
FORCEPROP 1 LAST TOLERANCE 10%
J 0
(-6800 6497);
DISPLAY 0.617021 (-6800 6497);
PAINT SKYBLUE (-6800 6497);
FORCEPROP 1 LAST PART_NUMBER CH5104KEB02
J 0
(-6800 6350);
DISPLAY 0.617021 (-6800 6350);
PAINT BLUE (-6800 6350);
FORCEPROP 2 LAST SEC_TYPE C0402
J 0
(-6950 6721);
DISPLAY 1.021277 (-6950 6721);
DISPLAY INVISIBLE (-6950 6721);
FORCEPROP 2 LAST SIGNAL_MODEL DEFAULT_CAPACITOR_100000PF_2_1
R 3
J 1
(-6970 6473);
DISPLAY 0.744681 (-6970 6473);
PAINT MONO (-6970 6473);
DISPLAY INVISIBLE (-6970 6473);
FORCEPROP 2 LAST CDS_LIB pure_quanta
J 0
(-6900 6525);
DISPLAY INVISIBLE (-6900 6525);
FORCEPROP 1 LAST PATH I10
J 2
(-6950 6675);
DISPLAY 0.978723 (-6950 6675);
PAINT WHITE (-6950 6675);
DISPLAY INVISIBLE (-6950 6675);
FORCEADD UNIVERSAL_POWER..1
(-6900 7025);
FORCEPROP 3 LASTPIN (-6900 6975) SIG_NAME P5V_AUX_VCC\g
J 0
(-6890 6985);
DISPLAY 0.659574 (-6890 6985);
PAINT MONO (-6890 6985);
DISPLAY INVISIBLE (-6890 6985);
FORCEPROP 1 LAST HDL_POWER P5V_AUX_VCC
J 1
(-6900 7075);
DISPLAY 0.617021 (-6900 7075);
PAINT GREEN (-6900 7075);
FORCEPROP 2 LAST CDS_LIB pure_quanta_power
J 0
(-6900 7025);
PAINT MONO (-6900 7025);
DISPLAY INVISIBLE (-6900 7025);
FORCEPROP 1 LAST PATH I11
J 0
(-6850 7050);
DISPLAY 0.872340 (-6850 7050);
PAINT AQUA (-6850 7050);
DISPLAY INVISIBLE (-6850 7050);
FORCEADD Q_CAP..1
(-7075 7800);
FORCEPROP 1 LAST LOCATION PC1850
J 0
(-7025 7900);
DISPLAY 0.617021 (-7025 7900);
PAINT AQUA (-7025 7900);
FORCEPROP 0 LAST $SEC 1
J 0
(-7025 7950);
DISPLAY 0.680851 (-7025 7950);
PAINT MONO (-7025 7950);
DISPLAY INVISIBLE (-7025 7950);
FORCEPROP 0 LAST CDS_SEC 1
J 0
(-7025 7950);
DISPLAY 1.021277 (-7025 7950);
DISPLAY INVISIBLE (-7025 7950);
FORCEPROP 1 LASTPIN (-7075 7900) $PN 1
J 0
(-7065 7880);
DISPLAY 0.617021 (-7065 7880);
PAINT MONO (-7065 7880);
FORCEPROP 1 LASTPIN (-7075 7700) $PN 2
J 0
(-7065 7680);
DISPLAY 0.617021 (-7065 7680);
PAINT MONO (-7065 7680);
FORCEPROP 1 LAST PART_NUMBER CH6223MEA01
J 0
(-7025 7650);
DISPLAY 0.617021 (-7025 7650);
PAINT BLUE (-7025 7650);
FORCEPROP 1 LAST VALUE 22UF
J 0
(-7025 7850);
DISPLAY 0.617021 (-7025 7850);
PAINT SKYBLUE (-7025 7850);
FORCEPROP 1 LAST MATERIAL X6S
J 0
(-7025 7700);
DISPLAY 0.617021 (-7025 7700);
PAINT SKYBLUE (-7025 7700);
FORCEPROP 1 LAST TOLERANCE 20%
J 0
(-7025 7750);
DISPLAY 0.617021 (-7025 7750);
PAINT SKYBLUE (-7025 7750);
FORCEPROP 1 LAST VOLTAGE 16V
J 0
(-7025 7800);
DISPLAY 0.617021 (-7025 7800);
PAINT SKYBLUE (-7025 7800);
FORCEPROP 1 LAST PACK_TYPE C0805
J 0
(-7025 7600);
DISPLAY 0.617021 (-7025 7600);
PAINT SKYBLUE (-7025 7600);
FORCEPROP 2 LAST CDS_LIB pure_quanta
J 0
(-7075 7800);
DISPLAY INVISIBLE (-7075 7800);
FORCEPROP 1 LAST PATH I12
J 0
(-7025 7950);
DISPLAY 0.978723 (-7025 7950);
PAINT WHITE (-7025 7950);
DISPLAY INVISIBLE (-7025 7950);
FORCEADD Q_CAP..1
(-6625 7800);
FORCEPROP 1 LAST LOCATION PC1898
J 0
(-6575 7900);
DISPLAY 0.617021 (-6575 7900);
PAINT AQUA (-6575 7900);
FORCEPROP 0 LAST $SEC 1
J 0
(-6575 7950);
DISPLAY 0.680851 (-6575 7950);
PAINT MONO (-6575 7950);
DISPLAY INVISIBLE (-6575 7950);
FORCEPROP 0 LAST CDS_SEC 1
J 0
(-6575 7950);
DISPLAY 0.680851 (-6575 7950);
DISPLAY INVISIBLE (-6575 7950);
FORCEPROP 1 LASTPIN (-6625 7900) $PN 1
J 0
(-6615 7880);
DISPLAY 0.617021 (-6615 7880);
PAINT MONO (-6615 7880);
FORCEPROP 1 LASTPIN (-6625 7700) $PN 2
J 0
(-6615 7680);
DISPLAY 0.617021 (-6615 7680);
PAINT MONO (-6615 7680);
FORCEPROP 1 LAST MATERIAL X6S
J 0
(-6575 7700);
DISPLAY 0.617021 (-6575 7700);
PAINT SKYBLUE (-6575 7700);
FORCEPROP 1 LAST PACK_TYPE C0805
J 0
(-6575 7600);
DISPLAY 0.617021 (-6575 7600);
PAINT SKYBLUE (-6575 7600);
FORCEPROP 1 LAST TOLERANCE 20%
J 0
(-6575 7750);
DISPLAY 0.617021 (-6575 7750);
PAINT SKYBLUE (-6575 7750);
FORCEPROP 1 LAST VALUE 22UF
J 0
(-6575 7850);
DISPLAY 0.617021 (-6575 7850);
PAINT SKYBLUE (-6575 7850);
FORCEPROP 1 LAST VOLTAGE 16V
J 0
(-6575 7800);
DISPLAY 0.617021 (-6575 7800);
PAINT SKYBLUE (-6575 7800);
FORCEPROP 1 LAST PART_NUMBER CH6223MEA01
J 0
(-6575 7650);
DISPLAY 0.617021 (-6575 7650);
PAINT BLUE (-6575 7650);
FORCEPROP 2 LAST CDS_LIB pure_quanta
J 0
(-6625 7800);
DISPLAY INVISIBLE (-6625 7800);
FORCEPROP 1 LAST PATH I13
J 0
(-6575 7950);
DISPLAY 0.978723 (-6575 7950);
PAINT WHITE (-6575 7950);
DISPLAY INVISIBLE (-6575 7950);
FORCEADD OFFPAGE..1
(-6275 7250);
PAINT AQUA (-6275 7250);
FORCEPROP 2 LAST $XR2 244 
J 0
(-6797 7250);
DISPLAY 0.638298 (-6797 7250);
PAINT MONO (-6797 7250);
FORCEPROP 2 LAST $XR1 222 
J 0
(-6677 7250);
DISPLAY 0.638298 (-6677 7250);
PAINT MONO (-6677 7250);
FORCEPROP 2 LAST $XR0 259 
J 0
(-6557 7250);
DISPLAY 0.638298 (-6557 7250);
PAINT MONO (-6557 7250);
FORCEPROP 2 LAST CDS_LIB standard
J 0
(-6275 7250);
DISPLAY INVISIBLE (-6275 7250);
FORCEPROP 1 LAST OFFPAGE TRUE
J 0
(-5950 7125);
DISPLAY 0.872340 (-5950 7125);
PAINT AQUA (-5950 7125);
DISPLAY INVISIBLE (-5950 7125);
FORCEPROP 1 LAST COMMENT_BODY TRUE
J 0
(-6150 7150);
DISPLAY 0.872340 (-6150 7150);
PAINT GREEN (-6150 7150);
DISPLAY INVISIBLE (-6150 7150);
FORCEPROP 2 LAST PATH I14
J 0
(-6550 7300);
DISPLAY 1.021277 (-6550 7300);
DISPLAY INVISIBLE (-6550 7300);
FORCEADD Q_RES..1
(-6050 6950);
FORCEPROP 1 LAST LOCATION PR3337
J 0
(-6275 6975);
DISPLAY 0.638298 (-6275 6975);
FORCEPROP 0 LAST $SEC 1
J 0
(-5925 7025);
DISPLAY 0.680851 (-5925 7025);
PAINT MONO (-5925 7025);
DISPLAY INVISIBLE (-5925 7025);
FORCEPROP 0 LAST CDS_SEC 1
J 0
(-5925 7025);
DISPLAY 1.021277 (-5925 7025);
DISPLAY INVISIBLE (-5925 7025);
FORCEPROP 1 LASTPIN (-6150 6950) $PN 1
J 0
(-6138 6962);
DISPLAY 0.787234 (-6138 6962);
PAINT MONO (-6138 6962);
FORCEPROP 1 LASTPIN (-5950 6950) $PN 2
J 0
(-5988 6962);
DISPLAY 0.787234 (-5988 6962);
PAINT MONO (-5988 6962);
FORCEPROP 1 LAST PART_NUMBER CS00002JB13
J 0
(-6025 6850);
DISPLAY 0.638298 (-6025 6850);
FORCEPROP 1 LAST PACK_TYPE 0402LF
J 0
(-6250 6850);
DISPLAY 0.638298 (-6250 6850);
FORCEPROP 1 LAST VALUE 0
J 2
(-6025 6975);
DISPLAY 0.638298 (-6025 6975);
FORCEPROP 1 LAST TOLERANCE 5%
J 0
(-5925 6975);
DISPLAY 0.638298 (-5925 6975);
FORCEPROP 1 LAST MATERIAL CHIP
J 0
(-6250 6900);
DISPLAY 0.638298 (-6250 6900);
FORCEPROP 1 LAST WATTAGE 1/16W
J 2
(-5875 6900);
DISPLAY 0.638298 (-5875 6900);
FORCEPROP 2 LAST CDS_LIB pure_quanta
J 0
(-6050 6950);
DISPLAY INVISIBLE (-6050 6950);
FORCEPROP 1 LAST PATH I15
J 0
(-6100 7100);
DISPLAY 0.978723 (-6100 7100);
PAINT WHITE (-6100 7100);
DISPLAY INVISIBLE (-6100 7100);
FORCEADD MPQ8633AGLEC807Z..1
(-5075 7075);
FORCEPROP 1 LAST $LOCATION U326
J 0
(-5325 7900);
DISPLAY 0.723404 (-5325 7900);
PAINT GREEN (-5325 7900);
FORCEPROP 0 LAST CDS_LOCATION U326
J 0
(-5325 8150);
DISPLAY 1.021277 (-5325 8150);
DISPLAY INVISIBLE (-5325 8150);
FORCEPROP 0 LAST $SEC 1
J 0
(-5325 8150);
DISPLAY 0.680851 (-5325 8150);
PAINT MONO (-5325 8150);
DISPLAY INVISIBLE (-5325 8150);
FORCEPROP 0 LAST CDS_SEC 1
J 0
(-5300 8125);
DISPLAY 0.680851 (-5300 8125);
DISPLAY INVISIBLE (-5300 8125);
FORCEPROP 0 LASTPIN (-4675 6400) $PN 2
J 0
(-4665 6410);
DISPLAY 0.680851 (-4665 6410);
PAINT MONO (-4665 6410);
FORCEPROP 0 LASTPIN (-4675 7550) $PN 1
J 0
(-4665 7560);
DISPLAY 0.680851 (-4665 7560);
PAINT MONO (-4665 7560);
FORCEPROP 0 LASTPIN (-5475 6450) $PN 3
J 2
(-5485 6460);
DISPLAY 0.680851 (-5485 6460);
PAINT MONO (-5485 6460);
FORCEPROP 0 LASTPIN (-5475 7250) $PN 8
J 2
(-5485 7260);
DISPLAY 0.680851 (-5485 7260);
PAINT MONO (-5485 7260);
FORCEPROP 0 LASTPIN (-4675 6800) $PN 7
J 0
(-4665 6810);
DISPLAY 0.680851 (-4665 6810);
PAINT MONO (-4665 6810);
FORCEPROP 0 LASTPIN (-5475 7050) $PN 4
J 2
(-5485 7060);
DISPLAY 0.680851 (-5485 7060);
PAINT MONO (-5485 7060);
FORCEPROP 0 LASTPIN (-4675 6450) $PN 11_18
J 0
(-4665 6460);
DISPLAY 0.680851 (-4665 6460);
PAINT MONO (-4665 6460);
FORCEPROP 0 LASTPIN (-4675 7750) $PN 9
J 0
(-4665 7760);
DISPLAY 0.680851 (-4665 7760);
PAINT MONO (-4665 7760);
FORCEPROP 0 LASTPIN (-4675 6650) $PN 6
J 0
(-4665 6660);
DISPLAY 0.680851 (-4665 6660);
PAINT MONO (-4665 6660);
FORCEPROP 0 LASTPIN (-4675 7250) $PN 20
J 0
(-4665 7260);
DISPLAY 0.680851 (-4665 7260);
PAINT MONO (-4665 7260);
FORCEPROP 0 LASTPIN (-4675 6550) $PN 5
J 0
(-4665 6560);
DISPLAY 0.680851 (-4665 6560);
PAINT MONO (-4665 6560);
FORCEPROP 0 LASTPIN (-5475 6800) $PN 19
J 2
(-5485 6810);
DISPLAY 0.680851 (-5485 6810);
PAINT MONO (-5485 6810);
FORCEPROP 0 LASTPIN (-5475 7750) $PN 10
J 2
(-5485 7760);
DISPLAY 0.680851 (-5485 7760);
PAINT MONO (-5485 7760);
FORCEPROP 0 LASTPIN (-5475 7700) $PN 21
J 2
(-5485 7710);
DISPLAY 0.680851 (-5485 7710);
PAINT MONO (-5485 7710);
FORCEPROP 2 LAST PART_TYPE SMLF
J 0
(-5325 8100);
DISPLAY 0.680851 (-5325 8100);
FORCEPROP 1 LAST PART_NUMBER AL008633007
J 0
(-5322 7967);
DISPLAY 0.723404 (-5322 7967);
PAINT GREEN (-5322 7967);
FORCEPROP 1 LAST MATERIAL IC
J 0
(-5322 7840);
DISPLAY 0.723404 (-5322 7840);
PAINT GREEN (-5322 7840);
FORCEPROP 2 LAST VALUE MPQ8633AGLE-C807-Z
J 0
(-5325 8050);
DISPLAY 0.617021 (-5325 8050);
PAINT SKYBLUE (-5325 8050);
FORCEPROP 1 LAST NEEDS_NO_SIZE TRUE
J 0
(-5075 7075);
DISPLAY 0.723404 (-5075 7075);
PAINT GREEN (-5075 7075);
DISPLAY INVISIBLE (-5075 7075);
FORCEPROP 1 LAST CDS_LMAN_SYM_OUTLINE -250,725,250,-725
J 0
(-5075 7075);
DISPLAY 0.468085 (-5075 7075);
PAINT GREEN (-5075 7075);
DISPLAY INVISIBLE (-5075 7075);
FORCEPROP 2 LAST CDS_LIB pure_quanta
J 0
(-5075 7075);
DISPLAY INVISIBLE (-5075 7075);
FORCEPROP 1 LAST PATH I16
J 0
(-5075 7075);
DISPLAY 0.723404 (-5075 7075);
PAINT GREEN (-5075 7075);
DISPLAY INVISIBLE (-5075 7075);
FORCEADD GND..1
(-5650 6875);
FORCEPROP 3 LASTPIN (-5650 6925) SIG_NAME GND\g
J 0
(-5640 6935);
DISPLAY 0.659574 (-5640 6935);
PAINT MONO (-5640 6935);
DISPLAY INVISIBLE (-5640 6935);
FORCEPROP 1 LAST SIZE 1B
J 0
(-5575 6825);
DISPLAY 0.872340 (-5575 6825);
PAINT AQUA (-5575 6825);
DISPLAY INVISIBLE (-5575 6825);
FORCEPROP 2 LAST CDS_LIB pure_quanta_power
J 0
(-5650 6875);
DISPLAY INVISIBLE (-5650 6875);
FORCEPROP 1 LAST HDL_POWER GND
J 0
(-5650 7025);
DISPLAY 0.872340 (-5650 7025);
PAINT GREEN (-5650 7025);
DISPLAY INVISIBLE (-5650 7025);
FORCEPROP 1 LAST PATH I17
J 0
(-5575 6875);
DISPLAY 0.872340 (-5575 6875);
PAINT AQUA (-5575 6875);
DISPLAY INVISIBLE (-5575 6875);
FORCEADD Q_CAP..1
(-6225 7800);
FORCEPROP 1 LAST LOCATION PC1846
J 0
(-6175 7900);
DISPLAY 0.617021 (-6175 7900);
PAINT AQUA (-6175 7900);
FORCEPROP 0 LAST $SEC 1
J 0
(-6175 7950);
DISPLAY 0.680851 (-6175 7950);
PAINT MONO (-6175 7950);
DISPLAY INVISIBLE (-6175 7950);
FORCEPROP 0 LAST CDS_SEC 1
J 0
(-6175 7950);
DISPLAY 1.021277 (-6175 7950);
DISPLAY INVISIBLE (-6175 7950);
FORCEPROP 1 LASTPIN (-6225 7900) $PN 1
J 0
(-6215 7880);
DISPLAY 0.787234 (-6215 7880);
PAINT MONO (-6215 7880);
FORCEPROP 1 LASTPIN (-6225 7700) $PN 2
J 0
(-6215 7680);
DISPLAY 0.787234 (-6215 7680);
PAINT MONO (-6215 7680);
FORCEPROP 1 LAST VALUE 1UF
J 0
(-6175 7850);
DISPLAY 0.617021 (-6175 7850);
PAINT SKYBLUE (-6175 7850);
FORCEPROP 1 LAST PART_NUMBER CH5103KEB01
J 0
(-6175 7650);
DISPLAY 0.489362 (-6175 7650);
PAINT BLUE (-6175 7650);
FORCEPROP 1 LAST VOLTAGE 16V
J 0
(-6175 7800);
DISPLAY 0.617021 (-6175 7800);
PAINT SKYBLUE (-6175 7800);
FORCEPROP 1 LAST TOLERANCE 10%
J 0
(-6175 7750);
DISPLAY 0.617021 (-6175 7750);
PAINT SKYBLUE (-6175 7750);
FORCEPROP 1 LAST MATERIAL X6S
J 0
(-6175 7700);
DISPLAY 0.617021 (-6175 7700);
PAINT SKYBLUE (-6175 7700);
FORCEPROP 1 LAST PACK_TYPE C0402
J 0
(-6175 7600);
DISPLAY 0.617021 (-6175 7600);
PAINT SKYBLUE (-6175 7600);
FORCEPROP 2 LAST CDS_LIB pure_quanta
J 0
(-6225 7800);
DISPLAY INVISIBLE (-6225 7800);
FORCEPROP 1 LAST PATH I18
J 0
(-6175 7950);
DISPLAY 0.978723 (-6175 7950);
PAINT WHITE (-6175 7950);
DISPLAY INVISIBLE (-6175 7950);
FORCEADD GND..1
(-4450 6125);
FORCEPROP 3 LASTPIN (-4450 6175) SIG_NAME GND\g
J 0
(-4440 6185);
DISPLAY 0.659574 (-4440 6185);
PAINT MONO (-4440 6185);
DISPLAY INVISIBLE (-4440 6185);
FORCEPROP 2 LAST CDS_LIB pure_quanta_power
J 0
(-4450 6125);
DISPLAY INVISIBLE (-4450 6125);
FORCEPROP 1 LAST SIZE 1B
J 0
(-4375 6075);
DISPLAY 0.872340 (-4375 6075);
PAINT AQUA (-4375 6075);
DISPLAY INVISIBLE (-4375 6075);
FORCEPROP 1 LAST HDL_POWER GND
J 0
(-4450 6275);
DISPLAY 0.872340 (-4450 6275);
PAINT GREEN (-4450 6275);
DISPLAY INVISIBLE (-4450 6275);
FORCEPROP 1 LAST PATH I19
J 0
(-4375 6125);
DISPLAY 0.872340 (-4375 6125);
PAINT AQUA (-4375 6125);
DISPLAY INVISIBLE (-4375 6125);
FORCEADD GND..1
(-8250 7575);
FORCEPROP 3 LASTPIN (-8250 7625) SIG_NAME GND\g
J 0
(-8240 7635);
DISPLAY 0.659574 (-8240 7635);
PAINT MONO (-8240 7635);
DISPLAY INVISIBLE (-8240 7635);
FORCEPROP 2 LAST CDS_LIB pure_quanta_power
J 0
(-8250 7575);
DISPLAY INVISIBLE (-8250 7575);
FORCEPROP 1 LAST SIZE 1B
J 0
(-8175 7525);
DISPLAY 0.872340 (-8175 7525);
PAINT AQUA (-8175 7525);
DISPLAY INVISIBLE (-8175 7525);
FORCEPROP 1 LAST HDL_POWER GND
J 0
(-8250 7725);
DISPLAY 0.872340 (-8250 7725);
PAINT GREEN (-8250 7725);
DISPLAY INVISIBLE (-8250 7725);
FORCEPROP 1 LAST PATH I2
J 0
(-8175 7575);
DISPLAY 0.872340 (-8175 7575);
PAINT AQUA (-8175 7575);
DISPLAY INVISIBLE (-8175 7575);
FORCEADD GND..1
(-4325 6125);
FORCEPROP 3 LASTPIN (-4325 6175) SIG_NAME GND\g
J 0
(-4315 6185);
DISPLAY 0.659574 (-4315 6185);
PAINT MONO (-4315 6185);
DISPLAY INVISIBLE (-4315 6185);
FORCEPROP 2 LAST CDS_LIB pure_quanta_power
J 0
(-4325 6125);
DISPLAY INVISIBLE (-4325 6125);
FORCEPROP 1 LAST SIZE 1B
J 0
(-4250 6075);
DISPLAY 0.872340 (-4250 6075);
PAINT AQUA (-4250 6075);
DISPLAY INVISIBLE (-4250 6075);
FORCEPROP 1 LAST HDL_POWER GND
J 0
(-4325 6275);
DISPLAY 0.872340 (-4325 6275);
PAINT GREEN (-4325 6275);
DISPLAY INVISIBLE (-4325 6275);
FORCEPROP 1 LAST PATH I20
J 0
(-4250 6125);
DISPLAY 0.872340 (-4250 6125);
PAINT AQUA (-4250 6125);
DISPLAY INVISIBLE (-4250 6125);
FORCEADD GND..1
(-3900 6200);
FORCEPROP 3 LASTPIN (-3900 6250) SIG_NAME GND\g
J 0
(-3890 6260);
DISPLAY 0.659574 (-3890 6260);
PAINT MONO (-3890 6260);
DISPLAY INVISIBLE (-3890 6260);
FORCEPROP 2 LAST CDS_LIB pure_quanta_power
J 0
(-3900 6200);
DISPLAY INVISIBLE (-3900 6200);
FORCEPROP 1 LAST SIZE 1B
J 0
(-3825 6150);
DISPLAY 0.872340 (-3825 6150);
PAINT AQUA (-3825 6150);
DISPLAY INVISIBLE (-3825 6150);
FORCEPROP 1 LAST HDL_POWER GND
J 0
(-3900 6350);
DISPLAY 0.872340 (-3900 6350);
PAINT GREEN (-3900 6350);
DISPLAY INVISIBLE (-3900 6350);
FORCEPROP 1 LAST PATH I21
J 0
(-3825 6200);
DISPLAY 0.872340 (-3825 6200);
PAINT AQUA (-3825 6200);
DISPLAY INVISIBLE (-3825 6200);
FORCEADD GND..1
(-3750 6200);
FORCEPROP 3 LASTPIN (-3750 6250) SIG_NAME GND\g
J 0
(-3740 6260);
DISPLAY 0.659574 (-3740 6260);
PAINT MONO (-3740 6260);
DISPLAY INVISIBLE (-3740 6260);
FORCEPROP 2 LAST CDS_LIB pure_quanta_power
J 0
(-3750 6200);
DISPLAY INVISIBLE (-3750 6200);
FORCEPROP 1 LAST SIZE 1B
J 0
(-3675 6150);
DISPLAY 0.872340 (-3675 6150);
PAINT AQUA (-3675 6150);
DISPLAY INVISIBLE (-3675 6150);
FORCEPROP 1 LAST HDL_POWER GND
J 0
(-3750 6350);
DISPLAY 0.872340 (-3750 6350);
PAINT GREEN (-3750 6350);
DISPLAY INVISIBLE (-3750 6350);
FORCEPROP 1 LAST PATH I22
J 0
(-3675 6200);
DISPLAY 0.872340 (-3675 6200);
PAINT AQUA (-3675 6200);
DISPLAY INVISIBLE (-3675 6200);
FORCEADD Q_CAP..1
(-4325 6350);
FORCEPROP 1 LAST LOCATION PC1853
J 0
(-4275 6475);
DISPLAY 0.617021 (-4275 6475);
PAINT AQUA (-4275 6475);
FORCEPROP 2 LAST $SEC 1
J 0
(-4275 6550);
DISPLAY 0.680851 (-4275 6550);
PAINT MONO (-4275 6550);
DISPLAY INVISIBLE (-4275 6550);
FORCEPROP 2 LAST CDS_SEC 1
J 0
(-4275 6550);
DISPLAY 0.680851 (-4275 6550);
DISPLAY INVISIBLE (-4275 6550);
FORCEPROP 1 LASTPIN (-4325 6450) $PN 1
J 0
(-4315 6430);
DISPLAY 0.617021 (-4315 6430);
FORCEPROP 1 LASTPIN (-4325 6250) $PN 2
J 0
(-4315 6230);
DISPLAY 0.617021 (-4315 6230);
FORCEPROP 1 LAST VALUE 0.1UF
J 0
(-4275 6425);
DISPLAY 0.617021 (-4275 6425);
PAINT SKYBLUE (-4275 6425);
FORCEPROP 1 LAST VOLTAGE 25V
J 0
(-4275 6375);
DISPLAY 0.617021 (-4275 6375);
PAINT SKYBLUE (-4275 6375);
FORCEPROP 1 LAST PACK_TYPE 0402
J 0
(-4275 6175);
DISPLAY 0.617021 (-4275 6175);
PAINT SKYBLUE (-4275 6175);
FORCEPROP 1 LAST TOLERANCE 10%
J 0
(-4275 6325);
DISPLAY 0.617021 (-4275 6325);
PAINT SKYBLUE (-4275 6325);
FORCEPROP 1 LAST MATERIAL X7R
J 0
(-4275 6275);
DISPLAY 0.617021 (-4275 6275);
PAINT SKYBLUE (-4275 6275);
FORCEPROP 1 LAST PART_NUMBER CH4104K1B00
J 0
(-4275 6225);
DISPLAY 0.617021 (-4275 6225);
PAINT BLUE (-4275 6225);
FORCEPROP 2 LAST CDS_LIB pure_quanta
J 0
(-4325 6350);
DISPLAY INVISIBLE (-4325 6350);
FORCEPROP 1 LAST PATH I23
J 0
(-4275 6500);
DISPLAY 0.978723 (-4275 6500);
PAINT WHITE (-4275 6500);
DISPLAY INVISIBLE (-4275 6500);
FORCEADD Q_RES..2
(-3750 6525);
FORCEPROP 1 LAST LOCATION PR702
J 0
(-3705 6650);
DISPLAY 0.617021 (-3705 6650);
PAINT AQUA (-3705 6650);
FORCEPROP 2 LAST $SEC 1
J 0
(-3700 6750);
DISPLAY 0.680851 (-3700 6750);
PAINT MONO (-3700 6750);
DISPLAY INVISIBLE (-3700 6750);
FORCEPROP 2 LAST CDS_SEC 1
J 0
(-3700 6750);
DISPLAY 0.680851 (-3700 6750);
DISPLAY INVISIBLE (-3700 6750);
FORCEPROP 1 LASTPIN (-3750 6625) $PN 1
J 0
(-3745 6587);
DISPLAY 0.617021 (-3745 6587);
FORCEPROP 1 LASTPIN (-3750 6425) $PN 2
J 0
(-3745 6435);
DISPLAY 0.617021 (-3745 6435);
FORCEPROP 1 LAST WATTAGE 1/16W
J 0
(-3710 6500);
DISPLAY 0.617021 (-3710 6500);
PAINT SKYBLUE (-3710 6500);
FORCEPROP 1 LAST PACK_TYPE 0402LF
J 0
(-3710 6350);
DISPLAY 0.617021 (-3710 6350);
PAINT SKYBLUE (-3710 6350);
FORCEPROP 1 LAST TOLERANCE 0.1%
J 0
(-3705 6550);
DISPLAY 0.617021 (-3705 6550);
PAINT SKYBLUE (-3705 6550);
FORCEPROP 1 LAST VALUE 11.8K
J 0
(-3705 6600);
DISPLAY 0.617021 (-3705 6600);
PAINT SKYBLUE (-3705 6600);
FORCEPROP 1 LAST PART_NUMBER CS31182BB06
J 0
(-3710 6400);
DISPLAY 0.617021 (-3710 6400);
PAINT BLUE (-3710 6400);
FORCEPROP 1 LAST MATERIAL CHIP
J 0
(-3710 6450);
DISPLAY 0.617021 (-3710 6450);
PAINT SKYBLUE (-3710 6450);
FORCEPROP 2 LAST CDS_LIB pure_quanta
J 0
(-3750 6525);
DISPLAY INVISIBLE (-3750 6525);
FORCEPROP 1 LAST PATH I24
J 0
(-3700 6700);
DISPLAY 0.978723 (-3700 6700);
PAINT WHITE (-3700 6700);
DISPLAY INVISIBLE (-3700 6700);
FORCEADD Q_CAP..1
(-3800 7400);
FORCEPROP 1 LAST LOCATION PC1847
J 0
(-3750 7575);
DISPLAY 0.617021 (-3750 7575);
PAINT AQUA (-3750 7575);
FORCEPROP 0 LAST $SEC 1
J 0
(-3750 7625);
DISPLAY 0.680851 (-3750 7625);
PAINT MONO (-3750 7625);
DISPLAY INVISIBLE (-3750 7625);
FORCEPROP 0 LAST CDS_SEC 1
J 0
(-3750 7625);
DISPLAY 1.021277 (-3750 7625);
DISPLAY INVISIBLE (-3750 7625);
FORCEPROP 1 LASTPIN (-3800 7500) $PN 1
J 0
(-3790 7480);
DISPLAY 0.787234 (-3790 7480);
PAINT MONO (-3790 7480);
FORCEPROP 1 LASTPIN (-3800 7300) $PN 2
J 0
(-3790 7280);
DISPLAY 0.787234 (-3790 7280);
PAINT MONO (-3790 7280);
FORCEPROP 1 LAST VOLTAGE 25V
J 0
(-3750 7475);
DISPLAY 0.617021 (-3750 7475);
PAINT SKYBLUE (-3750 7475);
FORCEPROP 1 LAST PACK_TYPE C0402
J 0
(-3750 7275);
DISPLAY 0.617021 (-3750 7275);
PAINT SKYBLUE (-3750 7275);
FORCEPROP 1 LAST MATERIAL X7R
J 0
(-3750 7375);
DISPLAY 0.617021 (-3750 7375);
PAINT SKYBLUE (-3750 7375);
FORCEPROP 1 LAST TOLERANCE 10%
J 0
(-3750 7425);
DISPLAY 0.617021 (-3750 7425);
PAINT SKYBLUE (-3750 7425);
FORCEPROP 1 LAST PART_NUMBER CH4224K1B01
J 0
(-3750 7325);
DISPLAY 0.617021 (-3750 7325);
PAINT BLUE (-3750 7325);
FORCEPROP 1 LAST VALUE 0.22UF
J 0
(-3750 7525);
DISPLAY 0.617021 (-3750 7525);
PAINT SKYBLUE (-3750 7525);
FORCEPROP 2 LAST CDS_LIB pure_quanta
J 0
(-3800 7400);
DISPLAY INVISIBLE (-3800 7400);
FORCEPROP 1 LAST PATH I25
J 0
(-3750 7550);
DISPLAY 0.978723 (-3750 7550);
PAINT WHITE (-3750 7550);
DISPLAY INVISIBLE (-3750 7550);
FORCEADD Q_RES..2
(-3800 8125);
FORCEPROP 1 LAST LOCATION R2356
J 0
(-3755 8250);
DISPLAY 0.617021 (-3755 8250);
PAINT AQUA (-3755 8250);
FORCEPROP 2 LAST SEC 1
J 0
(-3749 8354);
DISPLAY 0.680851 (-3749 8354);
PAINT MONO (-3749 8354);
DISPLAY INVISIBLE (-3749 8354);
FORCEPROP 1 LASTPIN (-3800 8225) $PN 1
J 0
(-3795 8187);
DISPLAY 0.617021 (-3795 8187);
FORCEPROP 1 LASTPIN (-3800 8025) $PN 2
J 0
(-3795 8035);
DISPLAY 0.617021 (-3795 8035);
FORCEPROP 1 LAST PACK_TYPE 0402LF
J 0
(-3760 7950);
DISPLAY 0.617021 (-3760 7950);
PAINT SKYBLUE (-3760 7950);
FORCEPROP 1 LAST VALUE 10K
J 0
(-3755 8200);
DISPLAY 0.617021 (-3755 8200);
PAINT SKYBLUE (-3755 8200);
FORCEPROP 1 LAST WATTAGE 1/16W
J 0
(-3760 8100);
DISPLAY 0.617021 (-3760 8100);
PAINT SKYBLUE (-3760 8100);
FORCEPROP 1 LAST MATERIAL CHIP
J 0
(-3760 8050);
DISPLAY 0.617021 (-3760 8050);
PAINT SKYBLUE (-3760 8050);
FORCEPROP 1 LAST PART_NUMBER CS31002FB08
J 0
(-3760 8000);
DISPLAY 0.617021 (-3760 8000);
PAINT BLUE (-3760 8000);
FORCEPROP 1 LAST TOLERANCE 1%
J 0
(-3755 8150);
DISPLAY 0.617021 (-3755 8150);
PAINT SKYBLUE (-3755 8150);
FORCEPROP 2 LAST SEC_TYPE 0402LF
J 0
(-3749 8354);
DISPLAY 1.021277 (-3749 8354);
DISPLAY INVISIBLE (-3749 8354);
FORCEPROP 2 LAST CDS_LIB pure_quanta
R 3
J 0
(-3800 8125);
PAINT MONO (-3800 8125);
DISPLAY INVISIBLE (-3800 8125);
FORCEPROP 1 LAST PATH I26
J 0
(-3750 8300);
DISPLAY 0.978723 (-3750 8300);
PAINT WHITE (-3750 8300);
DISPLAY INVISIBLE (-3750 8300);
FORCEADD Q_RES..1
(-3225 7750);
FORCEPROP 1 LAST LOCATION R2316
J 0
(-3450 7750);
DISPLAY 0.638298 (-3450 7750);
FORCEPROP 0 LAST $SEC 1
J 0
(-3350 7950);
DISPLAY 0.680851 (-3350 7950);
PAINT MONO (-3350 7950);
DISPLAY INVISIBLE (-3350 7950);
FORCEPROP 0 LAST CDS_SEC 1
J 0
(-3350 7950);
DISPLAY 1.021277 (-3350 7950);
DISPLAY INVISIBLE (-3350 7950);
FORCEPROP 1 LASTPIN (-3325 7750) $PN 1
J 0
(-3313 7762);
DISPLAY 0.787234 (-3313 7762);
PAINT MONO (-3313 7762);
FORCEPROP 1 LASTPIN (-3125 7750) $PN 2
J 0
(-3163 7762);
DISPLAY 0.787234 (-3163 7762);
PAINT MONO (-3163 7762);
FORCEPROP 1 LAST PACK_TYPE 0402LF
J 0
(-3350 7900);
DISPLAY 0.617021 (-3350 7900);
PAINT SKYBLUE (-3350 7900);
FORCEPROP 1 LAST TOLERANCE 5%
J 0
(-3050 7750);
DISPLAY 0.617021 (-3050 7750);
PAINT SKYBLUE (-3050 7750);
FORCEPROP 1 LAST MATERIAL CHIP
J 0
(-3350 7850);
DISPLAY 0.617021 (-3350 7850);
PAINT SKYBLUE (-3350 7850);
FORCEPROP 1 LAST WATTAGE 1/16W
J 2
(-3050 7850);
DISPLAY 0.617021 (-3050 7850);
PAINT SKYBLUE (-3050 7850);
FORCEPROP 1 LAST VALUE 0
J 2
(-3075 7750);
DISPLAY 0.617021 (-3075 7750);
PAINT SKYBLUE (-3075 7750);
FORCEPROP 1 LAST PART_NUMBER CS00002JB13
J 0
(-3350 7800);
DISPLAY 0.617021 (-3350 7800);
PAINT BLUE (-3350 7800);
FORCEPROP 2 LAST CDS_LIB pure_quanta
J 0
(-3225 7750);
DISPLAY INVISIBLE (-3225 7750);
FORCEPROP 1 LAST PATH I27
J 0
(-3275 7900);
DISPLAY 0.978723 (-3275 7900);
PAINT WHITE (-3275 7900);
DISPLAY INVISIBLE (-3275 7900);
FORCEADD Q_CAP..2
(-2400 6125);
FORCEPROP 1 LAST LOCATION PC1877
J 1
(-2400 6225);
DISPLAY 0.617021 (-2400 6225);
PAINT AQUA (-2400 6225);
FORCEPROP 0 LAST $SEC 1
J 0
(-2400 6275);
DISPLAY 0.680851 (-2400 6275);
PAINT MONO (-2400 6275);
DISPLAY INVISIBLE (-2400 6275);
FORCEPROP 0 LAST CDS_SEC 1
J 0
(-2400 6275);
DISPLAY 0.680851 (-2400 6275);
DISPLAY INVISIBLE (-2400 6275);
FORCEPROP 1 LASTPIN (-2500 6125) $PN 1
J 0
(-2510 6140);
DISPLAY 0.617021 (-2510 6140);
PAINT MONO (-2510 6140);
FORCEPROP 1 LASTPIN (-2300 6125) $PN 2
J 0
(-2315 6140);
DISPLAY 0.617021 (-2315 6140);
PAINT MONO (-2315 6140);
FORCEPROP 1 LAST PART_NUMBER TMP_QCH04706JB01
J 1
(-2400 6175);
DISPLAY 0.617021 (-2400 6175);
PAINT BLUE (-2400 6175);
FORCEPROP 1 LAST VALUE 47PF
J 2
(-2400 6025);
DISPLAY 0.617021 (-2400 6025);
PAINT SKYBLUE (-2400 6025);
FORCEPROP 1 LAST VOLTAGE 50V
J 0
(-2400 6025);
DISPLAY 0.617021 (-2400 6025);
PAINT SKYBLUE (-2400 6025);
FORCEPROP 1 LAST PACK_TYPE 0402
J 1
(-2400 5925);
DISPLAY 0.617021 (-2400 5925);
PAINT SKYBLUE (-2400 5925);
FORCEPROP 1 LAST TOLERANCE 5%
J 2
(-2400 5975);
DISPLAY 0.617021 (-2400 5975);
PAINT SKYBLUE (-2400 5975);
FORCEPROP 1 LAST MATERIAL NPO
J 0
(-2400 5975);
DISPLAY 0.617021 (-2400 5975);
PAINT SKYBLUE (-2400 5975);
FORCEPROP 2 LAST CDS_LIB pure_quanta
J 0
(-2400 6125);
DISPLAY INVISIBLE (-2400 6125);
FORCEPROP 1 LAST PATH I28
J 0
(-2400 6325);
DISPLAY 0.978723 (-2400 6325);
PAINT WHITE (-2400 6325);
DISPLAY INVISIBLE (-2400 6325);
FORCEADD Q_RES..1
(-2375 6450);
FORCEPROP 1 LAST LOCATION PR703
J 0
(-2753 6479);
DISPLAY 0.617021 (-2753 6479);
PAINT AQUA (-2753 6479);
FORCEPROP 2 LAST $SEC 1
J 0
(-2402 6663);
DISPLAY 0.680851 (-2402 6663);
PAINT MONO (-2402 6663);
DISPLAY INVISIBLE (-2402 6663);
FORCEPROP 2 LAST CDS_SEC 1
J 0
(-2402 6663);
DISPLAY 0.680851 (-2402 6663);
DISPLAY INVISIBLE (-2402 6663);
FORCEPROP 1 LASTPIN (-2475 6450) $PN 1
J 0
(-2463 6462);
DISPLAY 0.617021 (-2463 6462);
FORCEPROP 1 LASTPIN (-2275 6450) $PN 2
J 0
(-2313 6462);
DISPLAY 0.617021 (-2313 6462);
FORCEPROP 1 LAST VALUE 86.6K
J 2
(-2050 6500);
DISPLAY 0.617021 (-2050 6500);
PAINT SKYBLUE (-2050 6500);
FORCEPROP 1 LAST PART_NUMBER CS38662FB05
J 0
(-2275 6400);
DISPLAY 0.617021 (-2275 6400);
PAINT BLUE (-2275 6400);
FORCEPROP 1 LAST MATERIAL CHIP
J 0
(-2675 6350);
DISPLAY 0.617021 (-2675 6350);
PAINT SKYBLUE (-2675 6350);
FORCEPROP 1 LAST TOLERANCE 1%
J 0
(-2275 6350);
DISPLAY 0.638298 (-2275 6350);
PAINT SKYBLUE (-2275 6350);
FORCEPROP 1 LAST PACK_TYPE 0402LF
J 0
(-2688 6386);
DISPLAY 0.617021 (-2688 6386);
PAINT SKYBLUE (-2688 6386);
FORCEPROP 2 LAST CDS_LIB pure_quanta
J 0
(-2375 6450);
DISPLAY INVISIBLE (-2375 6450);
FORCEPROP 1 LAST WATTAGE 1/16W
J 2
(-1801 6468);
DISPLAY 0.978723 (-1801 6468);
PAINT SKYBLUE (-1801 6468);
DISPLAY INVISIBLE (-1801 6468);
FORCEPROP 1 LAST PATH I29
J 0
(-2425 6600);
DISPLAY 0.978723 (-2425 6600);
PAINT WHITE (-2425 6600);
DISPLAY INVISIBLE (-2425 6600);
FORCEADD P1V0_AUX..1
(-8246 8245);
FORCEPROP 3 LASTPIN (-8246 8195) SIG_NAME P12V_AUX\g
J 0
(-8236 8205);
DISPLAY 0.659574 (-8236 8205);
PAINT MONO (-8236 8205);
DISPLAY INVISIBLE (-8236 8205);
FORCEPROP 1 LAST HDL_POWER P12V_AUX
J 1
(-8235 8292);
DISPLAY 0.617021 (-8235 8292);
PAINT GREEN (-8235 8292);
FORCEPROP 2 LAST ROOM VR_DDR1_POWER_STAGE
J 0
(-8246 8345);
DISPLAY 0.978723 (-8246 8345);
FORCEPROP 2 LAST CDS_LIB pure_quanta_power
J 0
(-8246 8245);
DISPLAY INVISIBLE (-8246 8245);
FORCEPROP 1 LAST PATH I3
J 0
(-8196 8270);
DISPLAY 0.872340 (-8196 8270);
PAINT AQUA (-8196 8270);
DISPLAY INVISIBLE (-8196 8270);
FORCEADD Q_INDUCTOR..1
(-2900 7275);
FORCEPROP 1 LAST LOCATION PL81
J 0
(-3025 7435);
DISPLAY 0.617021 (-3025 7435);
PAINT AQUA (-3025 7435);
FORCEPROP 2 LAST $SEC 1
J 0
(-3025 7575);
DISPLAY 0.680851 (-3025 7575);
PAINT MONO (-3025 7575);
DISPLAY INVISIBLE (-3025 7575);
FORCEPROP 2 LAST CDS_SEC 1
J 0
(-3025 7575);
DISPLAY 0.680851 (-3025 7575);
DISPLAY INVISIBLE (-3025 7575);
FORCEPROP 2 LASTPIN (-3000 7250) $PN 1
J 2
(-3010 7260);
DISPLAY 0.617021 (-3010 7260);
FORCEPROP 2 LASTPIN (-2800 7250) $PN 2
J 0
(-2790 7260);
DISPLAY 0.617021 (-2790 7260);
FORCEPROP 2 LAST PACK_TYPE SMLF
J 0
(-3025 7525);
DISPLAY 0.617021 (-3025 7525);
PAINT SKYBLUE (-3025 7525);
FORCEPROP 2 LAST VALUE 4.7UH
J 0
(-3025 7475);
DISPLAY 0.617021 (-3025 7475);
PAINT SKYBLUE (-3025 7475);
FORCEPROP 1 LAST PART_NUMBER CV-47A0MZ10
J 0
(-3025 7385);
DISPLAY 0.617021 (-3025 7385);
PAINT BLUE (-3025 7385);
FORCEPROP 1 LAST MATERIAL IND
J 0
(-3025 7330);
DISPLAY 0.617021 (-3025 7330);
PAINT SKYBLUE (-3025 7330);
FORCEPROP 1 LAST NEEDS_NO_SIZE TRUE
J 0
(-2900 7275);
DISPLAY 0.468085 (-2900 7275);
PAINT GREEN (-2900 7275);
DISPLAY INVISIBLE (-2900 7275);
FORCEPROP 2 LAST CDS_LIB pure_quanta
J 0
(-2900 7275);
DISPLAY INVISIBLE (-2900 7275);
FORCEPROP 1 LAST PATH I30
J 0
(-2825 7330);
DISPLAY 0.723404 (-2825 7330);
PAINT GREEN (-2825 7330);
DISPLAY INVISIBLE (-2825 7330);
FORCEADD Q_CAPP..1
(-1625 7000);
FORCEPROP 1 LAST LOCATION PC1845
J 0
(-1575 7100);
DISPLAY 0.617021 (-1575 7100);
PAINT AQUA (-1575 7100);
FORCEPROP 0 LAST $SEC 1
J 0
(-1575 7150);
DISPLAY 0.680851 (-1575 7150);
PAINT MONO (-1575 7150);
DISPLAY INVISIBLE (-1575 7150);
FORCEPROP 0 LAST CDS_SEC 1
J 0
(-1575 7150);
DISPLAY 0.680851 (-1575 7150);
DISPLAY INVISIBLE (-1575 7150);
FORCEPROP 1 LASTPIN (-1625 7100) $PN 1
J 0
(-1615 7085);
DISPLAY 0.617021 (-1615 7085);
PAINT MONO (-1615 7085);
FORCEPROP 1 LASTPIN (-1625 6900) $PN 2
J 0
(-1615 6885);
DISPLAY 0.617021 (-1615 6885);
PAINT MONO (-1615 6885);
FORCEPROP 1 LAST MATERIAL ALUM
J 0
(-1575 6900);
DISPLAY 0.617021 (-1575 6900);
PAINT SKYBLUE (-1575 6900);
FORCEPROP 1 LAST PART_NUMBER CC72201MZ28
J 0
(-1575 6800);
DISPLAY 0.617021 (-1575 6800);
PAINT BLUE (-1575 6800);
FORCEPROP 1 LAST TOLERANCE 20%
J 0
(-1575 7000);
DISPLAY 0.617021 (-1575 7000);
PAINT SKYBLUE (-1575 7000);
FORCEPROP 1 LAST VOLTAGE 6.3V
J 0
(-1575 6950);
DISPLAY 0.617021 (-1575 6950);
PAINT SKYBLUE (-1575 6950);
FORCEPROP 1 LAST PACK_TYPE SMLF
J 0
(-1575 6850);
DISPLAY 0.617021 (-1575 6850);
PAINT SKYBLUE (-1575 6850);
FORCEPROP 1 LAST VALUE 220UF
J 0
(-1575 7050);
DISPLAY 0.617021 (-1575 7050);
PAINT SKYBLUE (-1575 7050);
FORCEPROP 2 LAST CDS_LIB pure_quanta
J 0
(-1625 7000);
DISPLAY INVISIBLE (-1625 7000);
FORCEPROP 1 LAST PATH I31
J 0
(-1575 7150);
DISPLAY 0.978723 (-1575 7150);
DISPLAY INVISIBLE (-1575 7150);
FORCEADD OFFPAGE..2
(-2150 7750);
FORCEPROP 2 LAST $XR0 213 
J 0
(-1961 7750);
DISPLAY 0.638298 (-1961 7750);
PAINT MONO (-1961 7750);
FORCEPROP 2 LAST CDS_LIB standard
J 0
(-2150 7750);
PAINT MONO (-2150 7750);
DISPLAY INVISIBLE (-2150 7750);
FORCEPROP 2 LAST BOM_COST VR_SYSTEM 
J 0
(-1800 7800);
DISPLAY 0.680851 (-1800 7800);
DISPLAY INVISIBLE (-1800 7800);
FORCEPROP 1 LAST OFFPAGE TRUE
J 0
(-1825 7625);
DISPLAY 0.531915 (-1825 7625);
PAINT GREEN (-1825 7625);
DISPLAY INVISIBLE (-1825 7625);
FORCEPROP 1 LAST COMMENT_BODY TRUE
J 0
(-2195 7655);
DISPLAY 0.531915 (-2195 7655);
PAINT GREEN (-2195 7655);
DISPLAY INVISIBLE (-2195 7655);
FORCEPROP 2 LAST PATH I32
J 0
(-1950 7800);
DISPLAY 1.021277 (-1950 7800);
DISPLAY INVISIBLE (-1950 7800);
FORCEADD UNIVERSAL_POWER..1
(-3800 8425);
FORCEPROP 1 LAST HDL_POWER P5V_AUX_VCC
J 1
(-3800 8475);
DISPLAY 0.617021 (-3800 8475);
PAINT GREEN (-3800 8475);
FORCEPROP 2 LAST CDS_LIB pure_quanta_power
J 0
(-3800 8425);
DISPLAY INVISIBLE (-3800 8425);
FORCEPROP 1 LAST PATH I33
J 0
(-3750 8450);
DISPLAY 0.872340 (-3750 8450);
PAINT AQUA (-3750 8450);
DISPLAY INVISIBLE (-3750 8450);
FORCEADD Q_CAP..1
(-1175 7000);
FORCEPROP 1 LAST LOCATION PC1855
J 0
(-1125 7100);
DISPLAY 0.617021 (-1125 7100);
PAINT AQUA (-1125 7100);
FORCEPROP 0 LAST $SEC 1
J 0
(-1125 7150);
DISPLAY 0.680851 (-1125 7150);
PAINT MONO (-1125 7150);
DISPLAY INVISIBLE (-1125 7150);
FORCEPROP 0 LAST CDS_SEC 1
J 0
(-1125 7150);
DISPLAY 0.680851 (-1125 7150);
DISPLAY INVISIBLE (-1125 7150);
FORCEPROP 1 LASTPIN (-1175 7100) $PN 1
J 0
(-1165 7080);
DISPLAY 0.617021 (-1165 7080);
PAINT MONO (-1165 7080);
FORCEPROP 1 LASTPIN (-1175 6900) $PN 2
J 0
(-1165 6880);
DISPLAY 0.617021 (-1165 6880);
PAINT MONO (-1165 6880);
FORCEPROP 1 LAST PART_NUMBER CH6222MEA01
J 0
(-1125 6850);
DISPLAY 0.617021 (-1125 6850);
PAINT BLUE (-1125 6850);
FORCEPROP 1 LAST VALUE 22UF
J 0
(-1125 7050);
DISPLAY 0.617021 (-1125 7050);
PAINT SKYBLUE (-1125 7050);
FORCEPROP 1 LAST PACK_TYPE C0805
J 0
(-1125 6800);
DISPLAY 0.617021 (-1125 6800);
PAINT SKYBLUE (-1125 6800);
FORCEPROP 1 LAST TOLERANCE 20%
J 0
(-1125 6950);
DISPLAY 0.617021 (-1125 6950);
PAINT SKYBLUE (-1125 6950);
FORCEPROP 1 LAST VOLTAGE 10V
J 0
(-1125 7000);
DISPLAY 0.617021 (-1125 7000);
PAINT SKYBLUE (-1125 7000);
FORCEPROP 1 LAST MATERIAL X6S
J 0
(-1125 6900);
DISPLAY 0.617021 (-1125 6900);
PAINT SKYBLUE (-1125 6900);
FORCEPROP 2 LAST CDS_LIB pure_quanta
J 0
(-1175 7000);
DISPLAY INVISIBLE (-1175 7000);
FORCEPROP 1 LAST PATH I34
J 0
(-1125 7150);
DISPLAY 0.978723 (-1125 7150);
PAINT WHITE (-1125 7150);
DISPLAY INVISIBLE (-1125 7150);
FORCEADD Q_CAP..1
(-675 7000);
FORCEPROP 1 LAST LOCATION PC1856
J 0
(-625 7100);
DISPLAY 0.617021 (-625 7100);
PAINT AQUA (-625 7100);
FORCEPROP 0 LAST $SEC 1
J 0
(-625 7150);
DISPLAY 0.680851 (-625 7150);
PAINT MONO (-625 7150);
DISPLAY INVISIBLE (-625 7150);
FORCEPROP 0 LAST CDS_SEC 1
J 0
(-625 7150);
DISPLAY 0.680851 (-625 7150);
DISPLAY INVISIBLE (-625 7150);
FORCEPROP 1 LASTPIN (-675 7100) $PN 1
J 0
(-665 7080);
DISPLAY 0.617021 (-665 7080);
PAINT MONO (-665 7080);
FORCEPROP 1 LASTPIN (-675 6900) $PN 2
J 0
(-665 6880);
DISPLAY 0.617021 (-665 6880);
PAINT MONO (-665 6880);
FORCEPROP 1 LAST PART_NUMBER CH6222MEA01
J 0
(-625 6850);
DISPLAY 0.617021 (-625 6850);
PAINT BLUE (-625 6850);
FORCEPROP 1 LAST MATERIAL X6S
J 0
(-625 6900);
DISPLAY 0.617021 (-625 6900);
PAINT SKYBLUE (-625 6900);
FORCEPROP 1 LAST PACK_TYPE C0805
J 0
(-625 6800);
DISPLAY 0.617021 (-625 6800);
PAINT SKYBLUE (-625 6800);
FORCEPROP 1 LAST VALUE 22UF
J 0
(-625 7050);
DISPLAY 0.617021 (-625 7050);
PAINT SKYBLUE (-625 7050);
FORCEPROP 1 LAST VOLTAGE 10V
J 0
(-625 7000);
DISPLAY 0.617021 (-625 7000);
PAINT SKYBLUE (-625 7000);
FORCEPROP 1 LAST TOLERANCE 20%
J 0
(-625 6950);
DISPLAY 0.617021 (-625 6950);
PAINT SKYBLUE (-625 6950);
FORCEPROP 2 LAST CDS_LIB pure_quanta
J 0
(-675 7000);
DISPLAY INVISIBLE (-675 7000);
FORCEPROP 1 LAST PATH I35
J 0
(-625 7150);
DISPLAY 0.978723 (-625 7150);
PAINT WHITE (-625 7150);
DISPLAY INVISIBLE (-625 7150);
FORCEADD GND..1
(-250 6600);
FORCEPROP 3 LASTPIN (-250 6650) SIG_NAME GND\g
J 0
(-240 6660);
DISPLAY 0.659574 (-240 6660);
PAINT MONO (-240 6660);
DISPLAY INVISIBLE (-240 6660);
FORCEPROP 2 LAST CDS_LIB pure_quanta_power
J 0
(-250 6600);
DISPLAY INVISIBLE (-250 6600);
FORCEPROP 1 LAST SIZE 1B
J 0
(-175 6550);
DISPLAY 0.872340 (-175 6550);
PAINT AQUA (-175 6550);
DISPLAY INVISIBLE (-175 6550);
FORCEPROP 1 LAST HDL_POWER GND
J 0
(-250 6750);
DISPLAY 0.872340 (-250 6750);
PAINT GREEN (-250 6750);
DISPLAY INVISIBLE (-250 6750);
FORCEPROP 1 LAST PATH I36
J 0
(-175 6600);
DISPLAY 0.872340 (-175 6600);
PAINT AQUA (-175 6600);
DISPLAY INVISIBLE (-175 6600);
FORCEADD Q_CAP..1
(-250 7000);
FORCEPROP 1 LAST LOCATION PC1852
J 0
(-200 7100);
DISPLAY 0.617021 (-200 7100);
PAINT AQUA (-200 7100);
FORCEPROP 2 LAST SEC 1
J 0
(-198 7207);
DISPLAY 0.680851 (-198 7207);
PAINT MONO (-198 7207);
DISPLAY INVISIBLE (-198 7207);
FORCEPROP 1 LASTPIN (-250 7100) $PN 1
J 0
(-240 7080);
DISPLAY 0.617021 (-240 7080);
FORCEPROP 1 LASTPIN (-250 6900) $PN 2
J 0
(-240 6880);
DISPLAY 0.617021 (-240 6880);
FORCEPROP 1 LAST PACK_TYPE 0402
J 0
(-200 6800);
DISPLAY 0.617021 (-200 6800);
PAINT SKYBLUE (-200 6800);
FORCEPROP 1 LAST PART_NUMBER CH4104K1B00
J 0
(-200 6850);
DISPLAY 0.617021 (-200 6850);
PAINT BLUE (-200 6850);
FORCEPROP 1 LAST MATERIAL X7R
J 0
(-200 6900);
DISPLAY 0.617021 (-200 6900);
PAINT SKYBLUE (-200 6900);
FORCEPROP 1 LAST TOLERANCE 10%
J 0
(-200 6950);
DISPLAY 0.617021 (-200 6950);
PAINT SKYBLUE (-200 6950);
FORCEPROP 1 LAST VALUE 0.1UF
J 0
(-200 7050);
DISPLAY 0.617021 (-200 7050);
PAINT SKYBLUE (-200 7050);
FORCEPROP 1 LAST VOLTAGE 25V
J 0
(-200 7000);
DISPLAY 0.617021 (-200 7000);
PAINT SKYBLUE (-200 7000);
FORCEPROP 2 LAST CDS_LIB pure_quanta
J 0
(-250 7000);
PAINT MONO (-250 7000);
DISPLAY INVISIBLE (-250 7000);
FORCEPROP 2 LAST SEC_TYPE 0402
J 0
(-200 7196);
DISPLAY 1.021277 (-200 7196);
DISPLAY INVISIBLE (-200 7196);
FORCEPROP 1 LAST PATH I37
J 0
(-200 7150);
DISPLAY 0.978723 (-200 7150);
PAINT WHITE (-200 7150);
DISPLAY INVISIBLE (-200 7150);
FORCEADD P1V0..1
(250 7725);
FORCEPROP 3 LASTPIN (250 7675) SIG_NAME P5V_AUX\g
J 0
(260 7685);
DISPLAY 0.659574 (260 7685);
PAINT MONO (260 7685);
DISPLAY INVISIBLE (260 7685);
FORCEPROP 1 LAST HDL_POWER P5V_AUX
J 1
(250 7775);
DISPLAY 0.617021 (250 7775);
PAINT GREEN (250 7775);
FORCEPROP 2 LAST CDS_LIB pure_quanta_power
J 0
(250 7725);
PAINT MONO (250 7725);
DISPLAY INVISIBLE (250 7725);
FORCEPROP 1 LAST PATH I38
J 0
(300 7750);
DISPLAY 0.872340 (300 7750);
PAINT AQUA (300 7750);
DISPLAY INVISIBLE (300 7750);
FORCEADD Q_INDUCTOR..1
(-7975 8050);
FORCEPROP 1 LAST LOCATION PL80
J 0
(-8100 8210);
DISPLAY 0.617021 (-8100 8210);
PAINT AQUA (-8100 8210);
FORCEPROP 0 LAST $SEC 1
J 0
(-8100 8350);
DISPLAY 0.680851 (-8100 8350);
PAINT MONO (-8100 8350);
DISPLAY INVISIBLE (-8100 8350);
FORCEPROP 0 LAST CDS_SEC 1
J 0
(-8100 8350);
DISPLAY 0.680851 (-8100 8350);
DISPLAY INVISIBLE (-8100 8350);
FORCEPROP 0 LASTPIN (-8075 8025) $PN 1
J 2
(-8085 8035);
DISPLAY 0.617021 (-8085 8035);
PAINT MONO (-8085 8035);
FORCEPROP 0 LASTPIN (-7875 8025) $PN 2
J 0
(-7865 8035);
DISPLAY 0.617021 (-7865 8035);
PAINT MONO (-7865 8035);
FORCEPROP 1 LAST MATERIAL IND
J 0
(-8100 8105);
DISPLAY 0.617021 (-8100 8105);
PAINT SKYBLUE (-8100 8105);
FORCEPROP 2 LAST PACK_TYPE SMLF
J 0
(-8100 8300);
DISPLAY 0.617021 (-8100 8300);
PAINT SKYBLUE (-8100 8300);
FORCEPROP 2 LAST VALUE BLM18SN220TN1D/8000MA
J 0
(-8100 8250);
DISPLAY 0.617021 (-8100 8250);
PAINT SKYBLUE (-8100 8250);
FORCEPROP 1 LAST PART_NUMBER CX220TN1001
J 0
(-8100 8160);
DISPLAY 0.617021 (-8100 8160);
PAINT BLUE (-8100 8160);
FORCEPROP 1 LAST NEEDS_NO_SIZE TRUE
J 0
(-7975 8050);
DISPLAY 0.468085 (-7975 8050);
PAINT GREEN (-7975 8050);
DISPLAY INVISIBLE (-7975 8050);
FORCEPROP 2 LAST CDS_LIB pure_quanta
J 0
(-7975 8050);
DISPLAY INVISIBLE (-7975 8050);
FORCEPROP 1 LAST PATH I4
J 0
(-7900 8105);
DISPLAY 0.723404 (-7900 8105);
PAINT GREEN (-7900 8105);
DISPLAY INVISIBLE (-7900 8105);
FORCEADD GND..1
(-7475 7425);
FORCEPROP 3 LASTPIN (-7475 7475) SIG_NAME GND\g
J 0
(-7465 7485);
DISPLAY 0.659574 (-7465 7485);
PAINT MONO (-7465 7485);
DISPLAY INVISIBLE (-7465 7485);
FORCEPROP 2 LAST CDS_LIB pure_quanta_power
J 0
(-7475 7425);
DISPLAY INVISIBLE (-7475 7425);
FORCEPROP 1 LAST SIZE 1B
J 0
(-7400 7375);
DISPLAY 0.872340 (-7400 7375);
PAINT AQUA (-7400 7375);
DISPLAY INVISIBLE (-7400 7375);
FORCEPROP 1 LAST HDL_POWER GND
J 0
(-7475 7575);
DISPLAY 0.872340 (-7475 7575);
PAINT GREEN (-7475 7575);
DISPLAY INVISIBLE (-7475 7575);
FORCEPROP 1 LAST PATH I5
J 0
(-7400 7425);
DISPLAY 0.872340 (-7400 7425);
PAINT AQUA (-7400 7425);
DISPLAY INVISIBLE (-7400 7425);
FORCEADD Q_CAP..1
(-7475 7800);
FORCEPROP 1 LAST LOCATION PC1849
J 0
(-7425 7900);
DISPLAY 0.617021 (-7425 7900);
PAINT AQUA (-7425 7900);
FORCEPROP 0 LAST $SEC 1
J 0
(-7425 7950);
DISPLAY 0.680851 (-7425 7950);
PAINT MONO (-7425 7950);
DISPLAY INVISIBLE (-7425 7950);
FORCEPROP 0 LAST CDS_SEC 1
J 0
(-7425 7950);
DISPLAY 1.021277 (-7425 7950);
DISPLAY INVISIBLE (-7425 7950);
FORCEPROP 1 LASTPIN (-7475 7900) $PN 1
J 0
(-7465 7880);
DISPLAY 0.617021 (-7465 7880);
PAINT MONO (-7465 7880);
FORCEPROP 1 LASTPIN (-7475 7700) $PN 2
J 0
(-7465 7680);
DISPLAY 0.617021 (-7465 7680);
PAINT MONO (-7465 7680);
FORCEPROP 1 LAST VALUE 22UF
J 0
(-7425 7850);
DISPLAY 0.617021 (-7425 7850);
PAINT SKYBLUE (-7425 7850);
FORCEPROP 1 LAST VOLTAGE 16V
J 0
(-7425 7800);
DISPLAY 0.617021 (-7425 7800);
PAINT SKYBLUE (-7425 7800);
FORCEPROP 1 LAST MATERIAL X6S
J 0
(-7425 7700);
DISPLAY 0.617021 (-7425 7700);
PAINT SKYBLUE (-7425 7700);
FORCEPROP 1 LAST PART_NUMBER CH6223MEA01
J 0
(-7425 7650);
DISPLAY 0.617021 (-7425 7650);
PAINT BLUE (-7425 7650);
FORCEPROP 1 LAST PACK_TYPE C0805
J 0
(-7425 7600);
DISPLAY 0.617021 (-7425 7600);
PAINT SKYBLUE (-7425 7600);
FORCEPROP 1 LAST TOLERANCE 20%
J 0
(-7425 7750);
DISPLAY 0.617021 (-7425 7750);
PAINT SKYBLUE (-7425 7750);
FORCEPROP 2 LAST CDS_LIB pure_quanta
J 0
(-7475 7800);
DISPLAY INVISIBLE (-7475 7800);
FORCEPROP 1 LAST PATH I6
J 0
(-7425 7950);
DISPLAY 0.978723 (-7425 7950);
PAINT WHITE (-7425 7950);
DISPLAY INVISIBLE (-7425 7950);
FORCEADD GND..1
(-6900 6150);
FORCEPROP 3 LASTPIN (-6900 6200) SIG_NAME GND\g
J 0
(-6890 6210);
DISPLAY 0.659574 (-6890 6210);
PAINT MONO (-6890 6210);
DISPLAY INVISIBLE (-6890 6210);
FORCEPROP 1 LAST SIZE 1B
J 0
(-6825 6100);
DISPLAY 0.872340 (-6825 6100);
PAINT AQUA (-6825 6100);
DISPLAY INVISIBLE (-6825 6100);
FORCEPROP 2 LAST CDS_LIB pure_quanta_power
J 0
(-6900 6150);
DISPLAY INVISIBLE (-6900 6150);
FORCEPROP 1 LAST HDL_POWER GND
J 0
(-6900 6300);
DISPLAY 0.872340 (-6900 6300);
PAINT GREEN (-6900 6300);
DISPLAY INVISIBLE (-6900 6300);
FORCEPROP 1 LAST PATH I7
J 0
(-6825 6150);
DISPLAY 0.872340 (-6825 6150);
PAINT AQUA (-6825 6150);
DISPLAY INVISIBLE (-6825 6150);
FORCEADD GND..1
(-5962 5943);
FORCEPROP 3 LASTPIN (-5962 5993) SIG_NAME GND\g
J 0
(-5952 6003);
DISPLAY 0.659574 (-5952 6003);
PAINT MONO (-5952 6003);
DISPLAY INVISIBLE (-5952 6003);
FORCEPROP 2 LAST CDS_LIB pure_quanta_power
J 0
(-5962 5943);
DISPLAY INVISIBLE (-5962 5943);
FORCEPROP 1 LAST SIZE 1B
J 0
(-5887 5893);
DISPLAY 0.872340 (-5887 5893);
PAINT AQUA (-5887 5893);
DISPLAY INVISIBLE (-5887 5893);
FORCEPROP 1 LAST HDL_POWER GND
J 0
(-5962 6093);
DISPLAY 0.872340 (-5962 6093);
PAINT GREEN (-5962 6093);
DISPLAY INVISIBLE (-5962 6093);
FORCEPROP 1 LAST PATH I8
J 0
(-5887 5943);
DISPLAY 0.872340 (-5887 5943);
PAINT AQUA (-5887 5943);
DISPLAY INVISIBLE (-5887 5943);
FORCEADD Q_RES..2
(-5962 6232);
FORCEPROP 1 LAST LOCATION PR701
J 0
(-5917 6357);
DISPLAY 0.617021 (-5917 6357);
PAINT AQUA (-5917 6357);
FORCEPROP 2 LAST SEC 1
J 0
(-5900 6475);
DISPLAY 0.680851 (-5900 6475);
PAINT MONO (-5900 6475);
DISPLAY INVISIBLE (-5900 6475);
FORCEPROP 1 LASTPIN (-5962 6332) $PN 1
J 0
(-5957 6294);
DISPLAY 0.617021 (-5957 6294);
FORCEPROP 1 LASTPIN (-5962 6132) $PN 2
J 0
(-5957 6142);
DISPLAY 0.617021 (-5957 6142);
FORCEPROP 1 LAST WATTAGE 1/16W
J 0
(-5922 6207);
DISPLAY 0.617021 (-5922 6207);
PAINT SKYBLUE (-5922 6207);
FORCEPROP 1 LAST MATERIAL CHIP
J 0
(-5922 6157);
DISPLAY 0.617021 (-5922 6157);
PAINT SKYBLUE (-5922 6157);
FORCEPROP 1 LAST TOLERANCE 1%
J 0
(-5917 6257);
DISPLAY 0.617021 (-5917 6257);
PAINT SKYBLUE (-5917 6257);
FORCEPROP 1 LAST VALUE 16.9K
J 0
(-5917 6307);
DISPLAY 0.617021 (-5917 6307);
PAINT SKYBLUE (-5917 6307);
FORCEPROP 1 LAST PACK_TYPE 0402LF
J 0
(-5922 6057);
DISPLAY 0.617021 (-5922 6057);
PAINT SKYBLUE (-5922 6057);
FORCEPROP 1 LAST PART_NUMBER CS31692FB03
J 0
(-5922 6107);
DISPLAY 0.617021 (-5922 6107);
PAINT BLUE (-5922 6107);
FORCEPROP 2 LAST CDS_LIB pure_quanta
R 3
J 0
(-5962 6232);
DISPLAY INVISIBLE (-5962 6232);
FORCEPROP 2 LAST SEC_TYPE 0402LF
J 0
(-5900 6475);
DISPLAY 1.021277 (-5900 6475);
DISPLAY INVISIBLE (-5900 6475);
FORCEPROP 1 LAST PATH I9
J 0
(-5912 6407);
DISPLAY 0.978723 (-5912 6407);
PAINT WHITE (-5912 6407);
DISPLAY INVISIBLE (-5912 6407);
FORCEADD QUANTA_TITLE_BLOCK_C..1
(750 4075);
FORCEPROP 0 LAST CDS_CON_LAST_MODIFIED Fri Mar 11 14:53:44 2022
J 0
(-1135 4090);
DISPLAY INVISIBLE (-1135 4090);
FORCEPROP 1 LAST CUSTOM_TXT_CDS <CON_LAST_MODIFIED>
J 0
(-1135 4090);
DISPLAY 0.978723 (-1135 4090);
FORCEPROP 2 LAST CUSTOM_TXT_CDS <XR_PAGE_TITLE>
J 0
(-7140 9325);
DISPLAY 0.638298 (-7140 9325);
PAINT PINK (-7140 9325);
DISPLAY INVISIBLE (-7140 9325);
FORCEPROP 1 LAST CUSTOM_TXT_CDS <NAME_2>
J 0
(-2425 4125);
FORCEPROP 1 LAST CUSTOM_TXT_CDS <NAME_1>
J 0
(-2425 4250);
FORCEPROP 1 LAST CUSTOM_TXT_CDS <Q_NUMBER>
J 0
(-653 4178);
DISPLAY 1.212766 (-653 4178);
FORCEPROP 1 LAST CUSTOM_TXT_CDS <Q_PROJ>
J 0
(-1632 4177);
DISPLAY 1.212766 (-1632 4177);
FORCEPROP 1 LAST CUSTOM_TXT_CDS <Q_REV>
J 0
(566 4178);
DISPLAY 1.212766 (566 4178);
FORCEPROP 1 LAST CUSTOM_TXT_CDS <CON_PAGE_NUM> OF <CON_TOTAL_PAGES>
J 0
(304 4093);
DISPLAY 0.978723 (304 4093);
FORCEPROP 1 LAST Q_DEPT BU9
J 1
(-3013 4124);
DISPLAY 1.957447 (-3013 4124);
PAINT GREEN (-3013 4124);
FORCEPROP 1 LAST Q_TITLE MPQ8633A/P5V_AUX
J 0
(-8525 4125);
DISPLAY 2.446809 (-8525 4125);
PAINT GREEN (-8525 4125);
FORCEPROP 2 LAST PAGE_BORDER TRUE
J 0
(-7140 9325);
DISPLAY 0.638298 (-7140 9325);
PAINT PINK (-7140 9325);
DISPLAY INVISIBLE (-7140 9325);
FORCEPROP 1 LAST CDS_LMAN_SYM_OUTLINE -9475,6775,100,-125
J 0
(750 4075);
DISPLAY 0.468085 (750 4075);
PAINT GREEN (750 4075);
DISPLAY INVISIBLE (750 4075);
FORCEPROP 2 LAST CDS_LIB pure_quanta
J 0
(750 4075);
DISPLAY INVISIBLE (750 4075);
FORCEPROP 1 LAST COMMENT_BODY TRUE
J 0
(762 4062);
DISPLAY 0.978723 (762 4062);
PAINT GREEN (762 4062);
DISPLAY INVISIBLE (762 4062);
FORCEPROP 2 LAST CDS_XR_PAGE_TITLE CR-258 : @S9S_MB_2U_LIB.S9S_MB_2U(SCH_1):PAGE258
J 0
(-7140 9325);
DISPLAY 0.638298 (-7140 9325);
PAINT PINK (-7140 9325);
DISPLAY INVISIBLE (-7140 9325);
WIRE 16 -1 (-5650 6950)(-5650 6925);
WIRE 16 -1 (-5950 6950)(-5650 6950);
WIRE 16 -1 (-8250 7625)(-8250 7725);
WIRE 16 -1 (-4325 6175)(-4325 6250);
WIRE 16 -1 (-3750 6425)(-3750 6250);
WIRE 16 -1 (-3800 8375)(-3800 8225);
FORCEPROP 2 LAST SIG_NAME P5V_AUX_VCC\G
J 0
(-3790 8385);
DISPLAY 0.659574 (-3790 8385);
DISPLAY INVISIBLE (-3790 8385);
WIRE 16 -1 (-6900 6200)(-6900 6425);
WIRE 16 -1 (-5962 5993)(-5962 6132);
WIRE 16 -1 (-3325 7750)(-3800 7750);
WIRE 16 -1 (-3800 8025)(-3800 7750);
WIRE 16 -1 (-3800 7750)(-4675 7750);
FORCEPROP 2 LAST SIG_NAME PWRGD_P5V_AUX_R
J 0
(-4585 7760);
DISPLAY 0.617021 (-4585 7760);
WIRE 16 -1 (-4675 7250)(-3800 7250);
FORCEPROP 2 LAST SIG_NAME SW_P5V_AUX_SW
J 0
(-4585 7260);
DISPLAY 0.617021 (-4585 7260);
WIRE 16 -1 (-3800 7250)(-3000 7250);
WIRE 16 -1 (-3800 7300)(-3800 7250);
WIRE 16 -1 (-1625 6900)(-1625 6750);
WIRE 16 -1 (-1175 6750)(-1625 6750);
WIRE 16 -1 (-675 6750)(-1175 6750);
WIRE 16 -1 (-1175 6900)(-1175 6750);
WIRE 16 -1 (-250 6750)(-675 6750);
WIRE 16 -1 (-675 6900)(-675 6750);
WIRE 16 -1 (-250 6650)(-250 6750);
WIRE 16 -1 (-250 6900)(-250 6750);
WIRE 16 -1 (-4675 6800)(-3750 6800);
FORCEPROP 2 LAST SIG_NAME P5V_AUX_FB
J 0
(-4585 6810);
DISPLAY 0.617021 (-4585 6810);
WIRE 16 -1 (-3000 6800)(-3750 6800);
WIRE 16 -1 (-3750 6625)(-3750 6800);
WIRE 16 -1 (-3000 6800)(-3000 6450);
WIRE 16 -1 (-3000 6450)(-3000 6125);
WIRE 16 -1 (-2475 6450)(-3000 6450);
WIRE 16 -1 (-2500 6125)(-3000 6125);
WIRE 16 -1 (-3900 6250)(-3900 6650);
WIRE 16 -1 (-3900 6650)(-4675 6650);
WIRE 16 -1 (-8250 7925)(-8250 8025);
WIRE 16 -1 (-8250 8025)(-8246 8025);
WIRE 16 -1 (-8075 8025)(-8246 8025);
WIRE 16 -1 (-8246 8195)(-8246 8025);
WIRE 16 -1 (-2800 7250)(-1625 7250);
WIRE 16 -1 (-1625 7250)(-1175 7250);
WIRE 16 -1 (-1625 7100)(-1625 7250);
WIRE 16 -1 (-675 7250)(-1175 7250);
WIRE 16 -1 (-1175 7250)(-1175 7100);
WIRE 16 -1 (-250 7250)(-675 7250);
WIRE 16 -1 (-675 7250)(-675 7100);
WIRE 16 -1 (250 7250)(-250 7250);
WIRE 16 -1 (-250 7100)(-250 7250);
WIRE 16 -1 (250 7250)(250 7675);
WIRE 16 -1 (250 7250)(250 6450);
WIRE 16 -1 (250 6450)(-1450 6450);
WIRE 16 -1 (-2275 6450)(-1450 6450);
WIRE 16 -1 (-1450 6125)(-1450 6450);
WIRE 16 -1 (-1450 6125)(-2300 6125);
WIRE 16 2175 (-8400 4625)(-7547 4625);
WIRE 16 2175 (-8400 4950)(-8400 4625);
WIRE 16 2175 (-7547 4950)(-7547 4625);
WIRE 16 2175 (-8400 4950)(-7547 4950);
WIRE 16 -1 (-6900 6975)(-6900 6800);
WIRE 16 -1 (-6900 6800)(-5475 6800);
WIRE 16 -1 (-6900 6625)(-6900 6800);
WIRE 16 -1 (-6225 7700)(-6225 7578);
WIRE 16 -1 (-6225 7578)(-6625 7578);
WIRE 16 -1 (-6625 7700)(-6625 7578);
WIRE 16 -1 (-6625 7578)(-7075 7578);
WIRE 16 -1 (-7075 7700)(-7075 7578);
WIRE 16 -1 (-7475 7578)(-7075 7578);
WIRE 16 -1 (-7475 7475)(-7475 7578);
WIRE 16 -1 (-7475 7700)(-7475 7578);
WIRE 16 -1 (-7875 8025)(-7475 8025);
WIRE 16 -1 (-7475 8025)(-7075 8025);
FORCEPROP 2 LAST SIG_NAME SW_P5V_AUX_FLT
J 0
(-6085 8035);
DISPLAY 0.617021 (-6085 8035);
WIRE 16 -1 (-7475 7900)(-7475 8025);
WIRE 16 -1 (-7075 8025)(-6625 8025);
WIRE 16 -1 (-7075 7900)(-7075 8025);
WIRE 16 -1 (-6625 8025)(-6225 8025);
WIRE 16 -1 (-6625 7900)(-6625 8025);
WIRE 16 -1 (-6225 8025)(-5650 8025);
WIRE 16 -1 (-6225 7900)(-6225 8025);
WIRE 16 -1 (-5650 8025)(-5650 7750);
WIRE 16 -1 (-5650 7750)(-5475 7750);
WIRE 16 -1 (-5650 7750)(-5650 7700);
WIRE 16 -1 (-5650 7700)(-5475 7700);
WIRE 16 3135 (-825 10025)(450 10025);
WIRE 16 3135 (-825 9425)(-825 10025);
WIRE 16 3135 (450 10025)(450 9425);
WIRE 16 3135 (-825 9425)(450 9425);
WIRE 16 -1 (-1119 6626)(-1119 6627);
WIRE 16 -1 (-2200 7750)(-3125 7750);
FORCEPROP 2 LAST SIG_NAME PWRGD_P5V_AUX
J 0
(-2735 7760);
DISPLAY 0.617021 (-2735 7760);
WIRE 16 -1 (-2832 5922)(-2832 5923);
WIRE 16 -1 (-3800 7500)(-3800 7550);
WIRE 16 -1 (-4675 7550)(-3800 7550);
FORCEPROP 2 LAST SIG_NAME SW_P5V_AUX_BST
J 0
(-4585 7560);
DISPLAY 0.617021 (-4585 7560);
WIRE 16 -1 (-4325 6550)(-4325 6450);
WIRE 16 -1 (-4675 6550)(-4325 6550);
FORCEPROP 2 LAST SIG_NAME P5V_AUX_REF
J 0
(-4585 6560);
DISPLAY 0.617021 (-4585 6560);
WIRE 16 -1 (-4450 6400)(-4450 6450);
WIRE 16 -1 (-4675 6400)(-4450 6400);
WIRE 16 -1 (-4450 6175)(-4450 6400);
WIRE 16 -1 (-4450 6450)(-4675 6450);
WIRE 16 -1 (-6225 7250)(-5475 7250);
FORCEPROP 2 LAST SIG_NAME PWRGD_P3V3_AUX
J 0
(-6085 7260);
DISPLAY 0.617021 (-6085 7260);
WIRE 16 -1 (-5962 6450)(-5475 6450);
WIRE 16 -1 (-5962 6332)(-5962 6450);
FORCEPROP 2 LAST SIG_NAME P5V_AUX_CS
J 0
(-6085 6460);
DISPLAY 0.617021 (-6085 6460);
WIRE 16 -1 (-6400 6950)(-6150 6950);
WIRE 16 -1 (-6400 7050)(-6400 6950);
WIRE 16 -1 (-5475 7050)(-6400 7050);
FORCEPROP 2 LAST SIG_NAME P5V_AUX_MODE
J 0
(-6085 7060);
DISPLAY 0.638298 (-6085 7060);
DOT 1 (250 7250);
DOT 1 (-250 7250);
DOT 1 (-675 7250);
DOT 1 (-1175 7250);
DOT 1 (-250 6750);
DOT 1 (-675 6750);
DOT 1 (-1175 6750);
DOT 1 (-1625 7250);
DOT 1 (-1450 6450);
DOT 1 (-3000 6450);
DOT 1 (-3800 7750);
DOT 1 (-3750 6800);
DOT 1 (-4450 6400);
DOT 1 (-5650 7750);
DOT 1 (-6225 8025);
DOT 1 (-6625 8025);
DOT 1 (-6625 7578);
DOT 1 (-7075 8025);
DOT 1 (-7075 7578);
DOT 1 (-6900 6800);
DOT 1 (-7475 8025);
DOT 1 (-7475 7578);
DOT 1 (-8246 8025);
DOT 1 (-3800 7250);
FORCENOTE
P5V_AUX
(-5850 9125) 0;
DISPLAY LEFT (-5850 9125);
DISPLAY 4.914894 (-5850 9125);
PAINT YELLOW (-5850 9125);
FORCENOTE
2ND AL000548006
(-8350 4684) 0;
DISPLAY LEFT (-8350 4684);
DISPLAY 1.021277 (-8350 4684);
PAINT WHITE (-8350 4684);
FORCENOTE
1ST AL008633007
(-8350 4750) 0;
DISPLAY LEFT (-8350 4750);
DISPLAY 1.021277 (-8350 4750);
PAINT WHITE (-8350 4750);
FORCENOTE
OUTPUT RIPPLE & NOISE = +/-1.0%
(-800 9800) 0;
DISPLAY LEFT (-800 9800);
DISPLAY 0.808511 (-800 9800);
PAINT WHITE (-800 9800);
FORCENOTE
OCP(IMAX*120%) = 4A
(-800 9600) 0;
DISPLAY LEFT (-800 9600);
DISPLAY 0.808511 (-800 9600);
PAINT RED (-800 9600);
FORCENOTE
DC TOLERANCE = +/-1.5%
(-800 9850) 0;
DISPLAY LEFT (-800 9850);
DISPLAY 0.808511 (-800 9850);
PAINT WHITE (-800 9850);
FORCENOTE
OUTPUT VOLTAGE = 5.0V
(-800 9900) 0;
DISPLAY LEFT (-800 9900);
DISPLAY 0.808511 (-800 9900);
PAINT WHITE (-800 9900);
FORCENOTE
DESIGN SPECIFICATION
(-800 9975) 0;
DISPLAY LEFT (-800 9975);
DISPLAY 0.808511 (-800 9975);
PAINT WHITE (-800 9975);
FORCENOTE
SLEW RATE = 1A/US
(-800 9500) 0;
DISPLAY LEFT (-800 9500);
DISPLAY 0.808511 (-800 9500);
PAINT WHITE (-800 9500);
FORCENOTE
WORK FREQUENCY = 600KHZ
(-800 9450) 0;
DISPLAY LEFT (-800 9450);
DISPLAY 0.808511 (-800 9450);
PAINT WHITE (-800 9450);
FORCENOTE
CURRENT STEP = 1A
(-800 9550) 0;
DISPLAY LEFT (-800 9550);
DISPLAY 0.808511 (-800 9550);
PAINT WHITE (-800 9550);
FORCENOTE
TRANSIENT TOLERANCE = +/-5.0%
(-800 9750) 0;
DISPLAY LEFT (-800 9750);
DISPLAY 0.808511 (-800 9750);
PAINT WHITE (-800 9750);
FORCENOTE
IMAX = 2.1A
(-800 9650) 0;
DISPLAY LEFT (-800 9650);
DISPLAY 0.808511 (-800 9650);
PAINT RED (-800 9650);
FORCENOTE
TDC = 1.8A
(-800 9700) 0;
DISPLAY LEFT (-800 9700);
DISPLAY 0.808511 (-800 9700);
PAINT RED (-800 9700);
FORCENOTE
RA
(-2425 6525) 0;
DISPLAY LEFT (-2425 6525);
DISPLAY 1.021277 (-2425 6525);
FORCENOTE
PCMB104E-4R7MS
(-3100 7150) 0;
DISPLAY LEFT (-3100 7150);
DISPLAY 1.021277 (-3100 7150);
FORCENOTE
10.3*11.2*4.0
(-3100 7100) 0;
DISPLAY LEFT (-3100 7100);
DISPLAY 1.021277 (-3100 7100);
FORCENOTE
ISAT=13A
(-3100 7050) 0;
DISPLAY LEFT (-3100 7050);
DISPLAY 1.021277 (-3100 7050);
FORCENOTE
VOUT=0.6(1+RA/RB)=5.003V
(-3545 5601) 0;
DISPLAY LEFT (-3545 5601);
DISPLAY 2.000000 (-3545 5601);
PAINT SKYBLUE (-3545 5601);
FORCENOTE
RB
(-3675 6725) 0;
DISPLAY LEFT (-3675 6725);
DISPLAY 1.021277 (-3675 6725);
FORCENOTE
IC TABLE
(-8375 4850) 0;
DISPLAY LEFT (-8375 4850);
DISPLAY 1.170213 (-8375 4850);
PAINT WHITE (-8375 4850);
FORCENOTE
DCR=15MOHM
(-3100 7000) 0;
DISPLAY LEFT (-3100 7000);
DISPLAY 1.021277 (-3100 7000);
QUIT
